(kicad_pcb
	(version 20260206)
	(generator "pcbnew")
	(generator_version "10.0")
	(general
		(thickness 1.6)
		(legacy_teardrops no)
	)
	(paper "A4")
	(title_block
		(title "03242023_DA0F0TMBIJ0_F0T_Motherboard_J_brd_V01_OCP.brd")
		(comment 1 "Grand Teton / footprints 5818-5822 of 6105")
	)
	(layers
		(0 "F.Cu" signal "TOP")
		(4 "In1.Cu" signal "GND")
		(6 "In2.Cu" signal "IN1")
		(8 "In3.Cu" signal "GND1")
		(10 "In4.Cu" signal "IN2")
		(12 "In5.Cu" signal "GND2")
		(14 "In6.Cu" signal "IN3")
		(16 "In7.Cu" signal "GND3")
		(18 "In8.Cu" signal "VCC")
		(20 "In9.Cu" signal "VCC1")
		(22 "In10.Cu" signal "GND4")
		(24 "In11.Cu" signal "IN4")
		(26 "In12.Cu" signal "GND5")
		(28 "In13.Cu" signal "IN5")
		(30 "In14.Cu" signal "GND6")
		(32 "In15.Cu" signal "IN6")
		(34 "In16.Cu" signal "GND7")
		(2 "B.Cu" signal "BOTTOM")
		(9 "F.Adhes" user "F.Adhesive")
		(11 "B.Adhes" user "B.Adhesive")
		(13 "F.Paste" user "Package Geometry/Pastemask Top")
		(15 "B.Paste" user "Package Geometry/Pastemask Bottom")
		(5 "F.SilkS" user "Ref Des/Silkscreen Top")
		(7 "B.SilkS" user "Ref Des/Silkscreen Bottom")
		(1 "F.Mask" user "Board Geometry/Soldermask Top")
		(3 "B.Mask" user "Board Geometry/Soldermask Bottom")
		(17 "Dwgs.User" user "User.Drawings")
		(19 "Cmts.User" user "User.Comments")
		(21 "Eco1.User" user "User.Eco1")
		(23 "Eco2.User" user "User.Eco2")
		(25 "Edge.Cuts" user "Board Geometry/Outline")
		(27 "Margin" user)
		(31 "F.CrtYd" user "Package Geometry/Place Bound Top")
		(29 "B.CrtYd" user "Package Geometry/Place Bound Bottom")
		(35 "F.Fab" user "Ref Des/Assembly Top")
		(33 "B.Fab" user "Ref Des/Assembly Bottom")
	)
	(footprint ""
		(layer "B.Cu")
		(at 156.1465 -192.77711 -90)
		(property "Reference" "R68"
			(at 0 0 90)
			(layer "B.SilkS")
			(hide yes)
			(effects
				(font
					(size 1.27 1.27)
				)
				(justify mirror)
			)
		)
		(property "Value" ""
			(at 0 0 90)
			(layer "B.Fab")
			(effects
				(font
					(size 1.27 1.27)
				)
				(justify mirror)
			)
		)
		(duplicate_pad_numbers_are_jumpers no)
		(fp_line
			(start -0.7874 0.4064)
			(end 0.7874 0.4064)
			(stroke
				(width 0.1524)
				(type default)
			)
			(layer "B.SilkS")
		)
		(fp_line
			(start 0.7874 0.4064)
			(end 0.7874 -0.4064)
			(stroke
				(width 0.1524)
				(type default)
			)
			(layer "B.SilkS")
		)
		(fp_line
			(start -0.7874 -0.4064)
			(end -0.7874 0.4064)
			(stroke
				(width 0.1524)
				(type default)
			)
			(layer "B.SilkS")
		)
		(fp_line
			(start 0.7874 -0.4064)
			(end -0.7874 -0.4064)
			(stroke
				(width 0.1524)
				(type default)
			)
			(layer "B.SilkS")
		)
		(fp_line
			(start -0.67945 0.3048)
			(end -0.120396 0.3048)
			(stroke
				(width 0.1)
				(type default)
			)
			(layer "B.Fab")
		)
		(fp_line
			(start -0.120396 0.3048)
			(end -0.120396 0.2794)
			(stroke
				(width 0.1)
				(type default)
			)
			(layer "B.Fab")
		)
		(fp_line
			(start 0.12065 0.3048)
			(end 0.67945 0.3048)
			(stroke
				(width 0.1)
				(type default)
			)
			(layer "B.Fab")
		)
		(fp_line
			(start 0.67945 0.3048)
			(end 0.67945 -0.305054)
			(stroke
				(width 0.1)
				(type default)
			)
			(layer "B.Fab")
		)
		(fp_line
			(start -0.120396 0.2794)
			(end 0.12065 0.2794)
			(stroke
				(width 0.1)
				(type default)
			)
			(layer "B.Fab")
		)
		(fp_line
			(start 0.12065 0.2794)
			(end 0.12065 0.3048)
			(stroke
				(width 0.1)
				(type default)
			)
			(layer "B.Fab")
		)
		(fp_line
			(start -0.12065 -0.2794)
			(end -0.12065 -0.3048)
			(stroke
				(width 0.1)
				(type default)
			)
			(layer "B.Fab")
		)
		(fp_line
			(start 0.12065 -0.2794)
			(end -0.12065 -0.2794)
			(stroke
				(width 0.1)
				(type default)
			)
			(layer "B.Fab")
		)
		(fp_line
			(start -0.67945 -0.3048)
			(end -0.67945 0.3048)
			(stroke
				(width 0.1)
				(type default)
			)
			(layer "B.Fab")
		)
		(fp_line
			(start -0.12065 -0.3048)
			(end -0.67945 -0.3048)
			(stroke
				(width 0.1)
				(type default)
			)
			(layer "B.Fab")
		)
		(fp_line
			(start 0.12065 -0.305054)
			(end 0.12065 -0.2794)
			(stroke
				(width 0.1)
				(type default)
			)
			(layer "B.Fab")
		)
		(fp_line
			(start 0.67945 -0.305054)
			(end 0.12065 -0.305054)
			(stroke
				(width 0.1)
				(type default)
			)
			(layer "B.Fab")
		)
		(pad "1" smd circle
			(at 0.40005 0 90)
			(size 0 0)
			(layers "B.Cu" "B.Mask" "B.Paste")
			(net "PWRGD_PLT_AUX_CPU1_LVT3_R")
		)
		(pad "2" smd circle
			(at -0.40005 0 90)
			(size 0 0)
			(layers "B.Cu" "B.Mask" "B.Paste")
			(net "PWRGD_PLT_AUX_CPU1_LVT3")
		)
	)
	(footprint ""
		(layer "B.Cu")
		(at 189.350396 -13.60043 -90)
		(property "Reference" "R594"
			(at 0 0 90)
			(layer "B.SilkS")
			(hide yes)
			(effects
				(font
					(size 1.27 1.27)
				)
				(justify mirror)
			)
		)
		(property "Value" ""
			(at 0 0 90)
			(layer "B.Fab")
			(effects
				(font
					(size 1.27 1.27)
				)
				(justify mirror)
			)
		)
		(duplicate_pad_numbers_are_jumpers no)
		(fp_line
			(start -0.7874 0.4064)
			(end 0.7874 0.4064)
			(stroke
				(width 0.1524)
				(type default)
			)
			(layer "B.SilkS")
		)
		(fp_line
			(start 0.7874 0.4064)
			(end 0.7874 -0.4064)
			(stroke
				(width 0.1524)
				(type default)
			)
			(layer "B.SilkS")
		)
		(fp_line
			(start -0.7874 -0.4064)
			(end -0.7874 0.4064)
			(stroke
				(width 0.1524)
				(type default)
			)
			(layer "B.SilkS")
		)
		(fp_line
			(start 0.7874 -0.4064)
			(end -0.7874 -0.4064)
			(stroke
				(width 0.1524)
				(type default)
			)
			(layer "B.SilkS")
		)
		(fp_line
			(start -0.67945 0.3048)
			(end -0.120396 0.3048)
			(stroke
				(width 0.1)
				(type default)
			)
			(layer "B.Fab")
		)
		(fp_line
			(start -0.120396 0.3048)
			(end -0.120396 0.2794)
			(stroke
				(width 0.1)
				(type default)
			)
			(layer "B.Fab")
		)
		(fp_line
			(start 0.12065 0.3048)
			(end 0.67945 0.3048)
			(stroke
				(width 0.1)
				(type default)
			)
			(layer "B.Fab")
		)
		(fp_line
			(start 0.67945 0.3048)
			(end 0.67945 -0.305054)
			(stroke
				(width 0.1)
				(type default)
			)
			(layer "B.Fab")
		)
		(fp_line
			(start -0.120396 0.2794)
			(end 0.12065 0.2794)
			(stroke
				(width 0.1)
				(type default)
			)
			(layer "B.Fab")
		)
		(fp_line
			(start 0.12065 0.2794)
			(end 0.12065 0.3048)
			(stroke
				(width 0.1)
				(type default)
			)
			(layer "B.Fab")
		)
		(fp_line
			(start -0.12065 -0.2794)
			(end -0.12065 -0.3048)
			(stroke
				(width 0.1)
				(type default)
			)
			(layer "B.Fab")
		)
		(fp_line
			(start 0.12065 -0.2794)
			(end -0.12065 -0.2794)
			(stroke
				(width 0.1)
				(type default)
			)
			(layer "B.Fab")
		)
		(fp_line
			(start -0.67945 -0.3048)
			(end -0.67945 0.3048)
			(stroke
				(width 0.1)
				(type default)
			)
			(layer "B.Fab")
		)
		(fp_line
			(start -0.12065 -0.3048)
			(end -0.67945 -0.3048)
			(stroke
				(width 0.1)
				(type default)
			)
			(layer "B.Fab")
		)
		(fp_line
			(start 0.12065 -0.305054)
			(end 0.12065 -0.2794)
			(stroke
				(width 0.1)
				(type default)
			)
			(layer "B.Fab")
		)
		(fp_line
			(start 0.67945 -0.305054)
			(end 0.12065 -0.305054)
			(stroke
				(width 0.1)
				(type default)
			)
			(layer "B.Fab")
		)
		(pad "1" smd circle
			(at 0.40005 0 90)
			(size 0 0)
			(layers "B.Cu" "B.Mask" "B.Paste")
			(net "I3C_SPD_DDRABCD_CPU0_BMC_R_SDA")
		)
		(pad "2" smd circle
			(at -0.40005 0 90)
			(size 0 0)
			(layers "B.Cu" "B.Mask" "B.Paste")
			(net "I3C_SPD_DDRABCD_CPU0_BMC_SDA")
		)
	)
	(footprint ""
		(layer "B.Cu")
		(at 211.634578 -316.14999 -90)
		(property "Reference" "D49"
			(at 4.116832 1.530858 0)
			(unlocked yes)
			(layer "B.SilkS")
			(effects
				(font
					(size 0.7874 0.5842)
					(thickness 0.1524)
				)
				(justify left mirror)
			)
		)
		(property "Value" ""
			(at 0 0 90)
			(layer "B.Fab")
			(effects
				(font
					(size 1.27 1.27)
				)
				(justify mirror)
			)
		)
		(duplicate_pad_numbers_are_jumpers no)
		(fp_line
			(start -2.050796 0.700024)
			(end 2.050796 0.700024)
			(stroke
				(width 0.1524)
				(type default)
			)
			(layer "B.SilkS")
		)
		(fp_line
			(start 2.050796 0.700024)
			(end 2.050796 -0.700024)
			(stroke
				(width 0.1524)
				(type default)
			)
			(layer "B.SilkS")
		)
		(fp_line
			(start -2.343404 0.6985)
			(end -2.216404 0.6985)
			(stroke
				(width 0.1524)
				(type default)
			)
			(layer "B.SilkS")
		)
		(fp_line
			(start -2.229104 0.6985)
			(end -2.051304 0.6985)
			(stroke
				(width 0.1524)
				(type default)
			)
			(layer "B.SilkS")
		)
		(fp_line
			(start -2.051304 0.6985)
			(end -2.051304 0.635)
			(stroke
				(width 0.1524)
				(type default)
			)
			(layer "B.SilkS")
		)
		(fp_line
			(start -2.152904 0.635)
			(end -2.152904 -0.6985)
			(stroke
				(width 0.1524)
				(type default)
			)
			(layer "B.SilkS")
		)
		(fp_line
			(start -2.051304 0.635)
			(end -2.152904 0.635)
			(stroke
				(width 0.1524)
				(type default)
			)
			(layer "B.SilkS")
		)
		(fp_line
			(start 0.30607 0.500126)
			(end -0.193802 0)
			(stroke
				(width 0.1524)
				(type default)
			)
			(layer "B.SilkS")
		)
		(fp_line
			(start -0.193802 0)
			(end 0.30607 -0.500126)
			(stroke
				(width 0.1524)
				(type default)
			)
			(layer "B.SilkS")
		)
		(fp_line
			(start -0.293878 -0.500126)
			(end -0.293878 0.500126)
			(stroke
				(width 0.1524)
				(type default)
			)
			(layer "B.SilkS")
		)
		(fp_line
			(start 0.30607 -0.500126)
			(end 0.30607 0.500126)
			(stroke
				(width 0.1524)
				(type default)
			)
			(layer "B.SilkS")
		)
		(fp_line
			(start -2.064004 -0.6731)
			(end -2.064004 -0.6985)
			(stroke
				(width 0.1524)
				(type default)
			)
			(layer "B.SilkS")
		)
		(fp_line
			(start -2.343404 -0.6985)
			(end -2.343404 0.6985)
			(stroke
				(width 0.1524)
				(type default)
			)
			(layer "B.SilkS")
		)
		(fp_line
			(start -2.229104 -0.6985)
			(end -2.229104 0.6985)
			(stroke
				(width 0.1524)
				(type default)
			)
			(layer "B.SilkS")
		)
		(fp_line
			(start -2.152904 -0.6985)
			(end -2.343404 -0.6985)
			(stroke
				(width 0.1524)
				(type default)
			)
			(layer "B.SilkS")
		)
		(fp_line
			(start -2.064004 -0.6985)
			(end -2.229104 -0.6985)
			(stroke
				(width 0.1524)
				(type default)
			)
			(layer "B.SilkS")
		)
		(fp_line
			(start -2.050796 -0.700024)
			(end -2.050796 0.700024)
			(stroke
				(width 0.1524)
				(type default)
			)
			(layer "B.SilkS")
		)
		(fp_line
			(start 2.050796 -0.700024)
			(end -2.050796 -0.700024)
			(stroke
				(width 0.1524)
				(type default)
			)
			(layer "B.SilkS")
		)
		(fp_line
			(start -0.899922 0.700024)
			(end 0.899922 0.700024)
			(stroke
				(width 0.1)
				(type default)
			)
			(layer "B.Fab")
		)
		(fp_line
			(start 0.899922 0.700024)
			(end 0.899922 -0.700024)
			(stroke
				(width 0.1)
				(type default)
			)
			(layer "B.Fab")
		)
		(fp_line
			(start -0.899922 -0.700024)
			(end -0.899922 0.700024)
			(stroke
				(width 0.1)
				(type default)
			)
			(layer "B.Fab")
		)
		(fp_line
			(start 0.899922 -0.700024)
			(end -0.899922 -0.700024)
			(stroke
				(width 0.1)
				(type default)
			)
			(layer "B.Fab")
		)
		(fp_text user "-"
			(at -0.268478 1.839468 90)
			(unlocked yes)
			(layer "B.SilkS")
			(effects
				(font
					(size 1.905 1.4224)
					(thickness 0.1524)
				)
				(justify left mirror)
			)
		)
		(fp_text user "+"
			(at 3.123946 0.762 180)
			(unlocked yes)
			(layer "B.SilkS")
			(effects
				(font
					(size 1.905 1.4224)
					(thickness 0.1524)
				)
				(justify left mirror)
			)
		)
		(fp_text user "+"
			(at 3.123946 0.762 180)
			(unlocked yes)
			(layer "B.Fab")
			(effects
				(font
					(size 1.905 1.4224)
					(thickness 0.1524)
				)
				(justify left mirror)
			)
		)
		(fp_text user "-"
			(at -3.880104 0.23495 90)
			(unlocked yes)
			(layer "B.Fab")
			(effects
				(font
					(size 1.905 1.4224)
					(thickness 0.1524)
				)
				(justify left mirror)
			)
		)
		(pad "1" smd rect
			(at 1.199896 0 180)
			(size 0.6604 1.3716)
			(layers "B.Cu" "B.Mask" "B.Paste")
			(net "PWRGD_FAIL_CPU1_GH_R1")
		)
		(pad "2" smd rect
			(at -1.199896 0)
			(size 0.6604 1.3716)
			(layers "B.Cu" "B.Mask" "B.Paste")
			(net "P3V3_AUX")
		)
	)
	(footprint ""
		(layer "B.Cu")
		(at 335.920588 -48.63338 90)
		(property "Reference" "C1183"
			(at 0 0 90)
			(layer "B.SilkS")
			(hide yes)
			(effects
				(font
					(size 1.27 1.27)
				)
				(justify mirror)
			)
		)
		(property "Value" ""
			(at 0 0 90)
			(layer "B.Fab")
			(effects
				(font
					(size 1.27 1.27)
				)
				(justify mirror)
			)
		)
		(duplicate_pad_numbers_are_jumpers no)
		(fp_line
			(start 0.7874 -0.4064)
			(end -0.7874 -0.4064)
			(stroke
				(width 0.1524)
				(type default)
			)
			(layer "B.SilkS")
		)
		(fp_line
			(start -0.7874 -0.4064)
			(end -0.7874 0.4064)
			(stroke
				(width 0.1524)
				(type default)
			)
			(layer "B.SilkS")
		)
		(fp_line
			(start 0.7874 0.4064)
			(end 0.7874 -0.4064)
			(stroke
				(width 0.1524)
				(type default)
			)
			(layer "B.SilkS")
		)
		(fp_line
			(start -0.7874 0.4064)
			(end 0.7874 0.4064)
			(stroke
				(width 0.1524)
				(type default)
			)
			(layer "B.SilkS")
		)
		(fp_line
			(start 0.67945 -0.305054)
			(end 0.12065 -0.305054)
			(stroke
				(width 0.1)
				(type default)
			)
			(layer "B.Fab")
		)
		(fp_line
			(start 0.12065 -0.305054)
			(end 0.12065 -0.2794)
			(stroke
				(width 0.1)
				(type default)
			)
			(layer "B.Fab")
		)
		(fp_line
			(start -0.12065 -0.3048)
			(end -0.67945 -0.3048)
			(stroke
				(width 0.1)
				(type default)
			)
			(layer "B.Fab")
		)
		(fp_line
			(start -0.67945 -0.3048)
			(end -0.67945 0.3048)
			(stroke
				(width 0.1)
				(type default)
			)
			(layer "B.Fab")
		)
		(fp_line
			(start 0.12065 -0.2794)
			(end -0.12065 -0.2794)
			(stroke
				(width 0.1)
				(type default)
			)
			(layer "B.Fab")
		)
		(fp_line
			(start -0.12065 -0.2794)
			(end -0.12065 -0.3048)
			(stroke
				(width 0.1)
				(type default)
			)
			(layer "B.Fab")
		)
		(fp_line
			(start 0.12065 0.2794)
			(end 0.12065 0.3048)
			(stroke
				(width 0.1)
				(type default)
			)
			(layer "B.Fab")
		)
		(fp_line
			(start -0.120396 0.2794)
			(end 0.12065 0.2794)
			(stroke
				(width 0.1)
				(type default)
			)
			(layer "B.Fab")
		)
		(fp_line
			(start 0.67945 0.3048)
			(end 0.67945 -0.305054)
			(stroke
				(width 0.1)
				(type default)
			)
			(layer "B.Fab")
		)
		(fp_line
			(start 0.12065 0.3048)
			(end 0.67945 0.3048)
			(stroke
				(width 0.1)
				(type default)
			)
			(layer "B.Fab")
		)
		(fp_line
			(start -0.120396 0.3048)
			(end -0.120396 0.2794)
			(stroke
				(width 0.1)
				(type default)
			)
			(layer "B.Fab")
		)
		(fp_line
			(start -0.67945 0.3048)
			(end -0.120396 0.3048)
			(stroke
				(width 0.1)
				(type default)
			)
			(layer "B.Fab")
		)
		(pad "1" smd circle
			(at 0.40005 0 270)
			(size 0 0)
			(layers "B.Cu" "B.Mask" "B.Paste")
			(net "P1V05_PCH_AUX")
		)
		(pad "2" smd circle
			(at -0.40005 0 270)
			(size 0 0)
			(layers "B.Cu" "B.Mask" "B.Paste")
			(net "GND")
		)
	)
	(footprint ""
		(layer "B.Cu")
		(at 79.414624 -184.096152 90)
		(property "Reference" "R345"
			(at 0 0 90)
			(layer "B.SilkS")
			(hide yes)
			(effects
				(font
					(size 1.27 1.27)
				)
				(justify mirror)
			)
		)
		(property "Value" ""
			(at 0 0 90)
			(layer "B.Fab")
			(effects
				(font
					(size 1.27 1.27)
				)
				(justify mirror)
			)
		)
		(duplicate_pad_numbers_are_jumpers no)
		(fp_line
			(start 0.7874 -0.4064)
			(end -0.7874 -0.4064)
			(stroke
				(width 0.1524)
				(type default)
			)
			(layer "B.SilkS")
		)
		(fp_line
			(start -0.7874 -0.4064)
			(end -0.7874 0.4064)
			(stroke
				(width 0.1524)
				(type default)
			)
			(layer "B.SilkS")
		)
		(fp_line
			(start 0.7874 0.4064)
			(end 0.7874 -0.4064)
			(stroke
				(width 0.1524)
				(type default)
			)
			(layer "B.SilkS")
		)
		(fp_line
			(start -0.7874 0.4064)
			(end 0.7874 0.4064)
			(stroke
				(width 0.1524)
				(type default)
			)
			(layer "B.SilkS")
		)
		(fp_line
			(start 0.67945 -0.305054)
			(end 0.12065 -0.305054)
			(stroke
				(width 0.1)
				(type default)
			)
			(layer "B.Fab")
		)
		(fp_line
			(start 0.12065 -0.305054)
			(end 0.12065 -0.2794)
			(stroke
				(width 0.1)
				(type default)
			)
			(layer "B.Fab")
		)
		(fp_line
			(start -0.12065 -0.3048)
			(end -0.67945 -0.3048)
			(stroke
				(width 0.1)
				(type default)
			)
			(layer "B.Fab")
		)
		(fp_line
			(start -0.67945 -0.3048)
			(end -0.67945 0.3048)
			(stroke
				(width 0.1)
				(type default)
			)
			(layer "B.Fab")
		)
		(fp_line
			(start 0.12065 -0.2794)
			(end -0.12065 -0.2794)
			(stroke
				(width 0.1)
				(type default)
			)
			(layer "B.Fab")
		)
		(fp_line
			(start -0.12065 -0.2794)
			(end -0.12065 -0.3048)
			(stroke
				(width 0.1)
				(type default)
			)
			(layer "B.Fab")
		)
		(fp_line
			(start 0.12065 0.2794)
			(end 0.12065 0.3048)
			(stroke
				(width 0.1)
				(type default)
			)
			(layer "B.Fab")
		)
		(fp_line
			(start -0.120396 0.2794)
			(end 0.12065 0.2794)
			(stroke
				(width 0.1)
				(type default)
			)
			(layer "B.Fab")
		)
		(fp_line
			(start 0.67945 0.3048)
			(end 0.67945 -0.305054)
			(stroke
				(width 0.1)
				(type default)
			)
			(layer "B.Fab")
		)
		(fp_line
			(start 0.12065 0.3048)
			(end 0.67945 0.3048)
			(stroke
				(width 0.1)
				(type default)
			)
			(layer "B.Fab")
		)
		(fp_line
			(start -0.120396 0.3048)
			(end -0.120396 0.2794)
			(stroke
				(width 0.1)
				(type default)
			)
			(layer "B.Fab")
		)
		(fp_line
			(start -0.67945 0.3048)
			(end -0.120396 0.3048)
			(stroke
				(width 0.1)
				(type default)
			)
			(layer "B.Fab")
		)
		(pad "1" smd circle
			(at 0.40005 0 270)
			(size 0 0)
			(layers "B.Cu" "B.Mask" "B.Paste")
			(net "H_CPU1_ERR2_LVC1_R_N")
		)
		(pad "2" smd circle
			(at -0.40005 0 270)
			(size 0 0)
			(layers "B.Cu" "B.Mask" "B.Paste")
			(net "H_CPU_ERR2_LVC1_R_N")
		)
	)
)
